FILE_TYPE = CONNECTIVITY;
{Allegro Design Entry HDL 17.2-2016 S081 (4005846) 1/11/2022}
"PAGE_NUMBER" = 9;
0"NC";
END.
